(kicad_pcb
	(version 20260206)
	(generator "pcbnew")
	(generator_version "10.0")
	(general
		(thickness 1.6)
		(legacy_teardrops no)
	)
	(paper "A4")
	(title_block
		(title "timecard-production-celestica-r4006 — R4006-B0001-02_R01.brd")
		(comment 1 "Time Appliance Project (Time Card) / footprints 522-524 of 1113")
	)
	(layers
		(0 "F.Cu" signal "TOP")
		(4 "In1.Cu" signal "L02_GND1")
		(6 "In2.Cu" signal "L03_SIG1")
		(8 "In3.Cu" signal "L04_GND2")
		(10 "In4.Cu" signal "L05_VCC1")
		(12 "In5.Cu" signal "L06_VCC2")
		(14 "In6.Cu" signal "L07_GND3")
		(16 "In7.Cu" signal "L08_SIG2")
		(18 "In8.Cu" signal "L09_GND4")
		(2 "B.Cu" signal "BOTTOM")
		(9 "F.Adhes" user "F.Adhesive")
		(11 "B.Adhes" user "B.Adhesive")
		(13 "F.Paste" user "Package Geometry/Pastemask Top")
		(15 "B.Paste" user "Package Geometry/Pastemask Bottom")
		(5 "F.SilkS" user "Ref Des/Silkscreen Top")
		(7 "B.SilkS" user "Ref Des/Silkscreen Bottom")
		(1 "F.Mask" user "Board Geometry/Soldermask Top")
		(3 "B.Mask" user "Board Geometry/Soldermask Bottom")
		(17 "Dwgs.User" user "User.Drawings")
		(19 "Cmts.User" user "User.Comments")
		(21 "Eco1.User" user "User.Eco1")
		(23 "Eco2.User" user "User.Eco2")
		(25 "Edge.Cuts" user "Board Geometry/Outline")
		(27 "Margin" user)
		(31 "F.CrtYd" user "Package Geometry/Place Bound Top")
		(29 "B.CrtYd" user "Package Geometry/Place Bound Bottom")
		(35 "F.Fab" user "Ref Des/Assembly Top")
		(33 "B.Fab" user "Ref Des/Assembly Bottom")
	)
	(footprint ""
		(layer "F.Cu")
		(at 20.4216 -53.1114 180)
		(property "Reference" "J18"
			(at -3.5814 0.31623 0)
			(unlocked yes)
			(layer "F.SilkS")
			(effects
				(font
					(size 0.7874 0.5842)
					(thickness 0.1524)
				)
			)
		)
		(property "Value" ""
			(at 0 0 180)
			(layer "F.Fab")
			(effects
				(font
					(size 1.27 1.27)
				)
			)
		)
		(property "User Part Number" "PARTNUM*"
			(at 0.126238 5.484368 180)
			(unlocked yes)
			(layer "Cmts.User")
			(hide yes)
			(effects
				(font
					(size 0.7874 0.5842)
					(thickness 0.1524)
				)
			)
		)
		(property "Device Type" "CONN_HDR_1X3_M_S_SMT-G205-1002A"
			(at 0.126238 4.290568 180)
			(unlocked yes)
			(layer "F.Fab")
			(hide yes)
			(effects
				(font
					(size 0.7874 0.5842)
					(thickness 0.1524)
				)
			)
		)
		(duplicate_pad_numbers_are_jumpers no)
		(fp_line
			(start 2.249678 2.299716)
			(end -2.249678 2.299716)
			(stroke
				(width 0.1)
				(type default)
			)
			(layer "F.SilkS")
		)
		(fp_line
			(start 2.249678 -1.67894)
			(end 2.249678 2.299716)
			(stroke
				(width 0.1)
				(type default)
			)
			(layer "F.SilkS")
		)
		(fp_line
			(start -2.249678 2.299716)
			(end -2.249678 -1.67894)
			(stroke
				(width 0.1)
				(type default)
			)
			(layer "F.SilkS")
		)
		(fp_line
			(start -2.249678 -1.67894)
			(end 2.249678 -1.67894)
			(stroke
				(width 0.1)
				(type default)
			)
			(layer "F.SilkS")
		)
		(fp_rect
			(start -2.503678 2.553716)
			(end 2.503678 -1.93294)
			(stroke
				(width 0)
				(type default)
			)
			(fill no)
			(layer "F.CrtYd")
		)
		(fp_line
			(start 1.42494 1.42494)
			(end 0.374904 1.42494)
			(stroke
				(width 0.1)
				(type default)
			)
			(layer "F.Fab")
		)
		(fp_line
			(start 1.42494 -1.42494)
			(end 1.42494 1.42494)
			(stroke
				(width 0.1)
				(type default)
			)
			(layer "F.Fab")
		)
		(fp_line
			(start 0.374904 1.674876)
			(end -0.374904 1.674876)
			(stroke
				(width 0.1)
				(type default)
			)
			(layer "F.Fab")
		)
		(fp_line
			(start 0.374904 1.42494)
			(end 0.374904 1.674876)
			(stroke
				(width 0.1)
				(type default)
			)
			(layer "F.Fab")
		)
		(fp_line
			(start -0.374904 1.674876)
			(end -0.374904 1.42494)
			(stroke
				(width 0.1)
				(type default)
			)
			(layer "F.Fab")
		)
		(fp_line
			(start -0.374904 1.42494)
			(end -1.42494 1.42494)
			(stroke
				(width 0.1)
				(type default)
			)
			(layer "F.Fab")
		)
		(fp_line
			(start -1.42494 1.42494)
			(end -1.42494 -1.42494)
			(stroke
				(width 0.1)
				(type default)
			)
			(layer "F.Fab")
		)
		(fp_line
			(start -1.42494 -1.42494)
			(end 1.42494 -1.42494)
			(stroke
				(width 0.1)
				(type default)
			)
			(layer "F.Fab")
		)
		(fp_text user "3"
			(at 2.6416 -0.69215 0)
			(unlocked yes)
			(layer "F.SilkS")
			(effects
				(font
					(size 0.635 0.4064)
					(thickness 0.1524)
				)
			)
		)
		(fp_text user "2"
			(at -2.5654 1.97485 0)
			(unlocked yes)
			(layer "F.SilkS")
			(effects
				(font
					(size 0.635 0.4064)
					(thickness 0.1524)
				)
			)
		)
		(fp_text user "1"
			(at -2.9464 -0.89535 0)
			(unlocked yes)
			(layer "F.SilkS")
			(effects
				(font
					(size 0.635 0.4064)
					(thickness 0.1524)
				)
			)
		)
		(fp_text user "3"
			(at 2.2606 0.96393 0)
			(unlocked yes)
			(layer "F.Fab")
			(effects
				(font
					(size 0.7874 0.5842)
					(thickness 0.1524)
				)
			)
		)
		(fp_text user "2"
			(at -1.0414 2.22123 0)
			(unlocked yes)
			(layer "F.Fab")
			(effects
				(font
					(size 0.7874 0.5842)
					(thickness 0.1524)
				)
			)
		)
		(fp_text user "1"
			(at -2.1844 0.07493 0)
			(unlocked yes)
			(layer "F.Fab")
			(effects
				(font
					(size 0.7874 0.5842)
					(thickness 0.1524)
				)
			)
		)
		(pad "1" smd rect
			(at -1.474978 0 180)
			(size 1.0414 2.2098)
			(layers "F.Cu" "F.Mask" "F.Paste")
			(net "SG")
		)
		(pad "2" smd rect
			(at 0 1.525016 180)
			(size 0.9906 1.0414)
			(layers "F.Cu" "F.Mask" "F.Paste")
			(net "SMA_ANALOG_TUNING_IN")
		)
		(pad "3" smd rect
			(at 1.474978 0 180)
			(size 1.0414 2.2098)
			(layers "F.Cu" "F.Mask" "F.Paste")
			(net "SG")
		)
	)
	(footprint ""
		(layer "F.Cu")
		(at 141.605 -54.737)
		(property "Reference" "U26"
			(at 0.127 -2.75463 0)
			(unlocked yes)
			(layer "F.SilkS")
			(effects
				(font
					(size 0.7874 0.5842)
					(thickness 0.1524)
				)
			)
		)
		(property "Value" ""
			(at 0 0 0)
			(layer "F.Fab")
			(effects
				(font
					(size 1.27 1.27)
				)
			)
		)
		(property "User Part Number" "PARTNUM*"
			(at 0.33782 5.715254 0)
			(unlocked yes)
			(layer "Cmts.User")
			(hide yes)
			(effects
				(font
					(size 0.7874 0.5842)
					(thickness 0.1524)
				)
			)
		)
		(property "Device Type" "TPS54824RNVR_VQFN18-G220-10657A"
			(at 0.33782 4.521454 0)
			(unlocked yes)
			(layer "F.Fab")
			(hide yes)
			(effects
				(font
					(size 0.7874 0.5842)
					(thickness 0.1524)
				)
			)
		)
		(duplicate_pad_numbers_are_jumpers no)
		(fp_line
			(start -2.208784 -2.208784)
			(end 2.208784 -2.208784)
			(stroke
				(width 0.1)
				(type default)
			)
			(layer "F.SilkS")
		)
		(fp_line
			(start -2.208784 2.200148)
			(end -2.208784 -2.208784)
			(stroke
				(width 0.1)
				(type default)
			)
			(layer "F.SilkS")
		)
		(fp_line
			(start 2.208784 -2.208784)
			(end 2.208784 2.200148)
			(stroke
				(width 0.1)
				(type default)
			)
			(layer "F.SilkS")
		)
		(fp_line
			(start 2.208784 2.200148)
			(end -2.208784 2.200148)
			(stroke
				(width 0.1)
				(type default)
			)
			(layer "F.SilkS")
		)
		(fp_poly
			(pts
				(arc
					(start -2.576068 -0.99314)
					(mid -3.592068 -0.99314)
					(end -2.576068 -0.99314)
				)
			)
			(stroke
				(width 0)
				(type default)
			)
			(fill yes)
			(layer "F.SilkS")
		)
		(fp_rect
			(start -2.462784 2.454148)
			(end 2.462784 -2.462784)
			(stroke
				(width 0)
				(type default)
			)
			(fill no)
			(layer "F.CrtYd")
		)
		(fp_line
			(start -1.800098 -1.800098)
			(end 1.800098 -1.800098)
			(stroke
				(width 0.1)
				(type default)
			)
			(layer "F.Fab")
		)
		(fp_line
			(start -1.800098 1.800098)
			(end -1.800098 -1.800098)
			(stroke
				(width 0.1)
				(type default)
			)
			(layer "F.Fab")
		)
		(fp_line
			(start 1.800098 -1.800098)
			(end 1.800098 1.800098)
			(stroke
				(width 0.1)
				(type default)
			)
			(layer "F.Fab")
		)
		(fp_line
			(start 1.800098 1.800098)
			(end -1.800098 1.800098)
			(stroke
				(width 0.1)
				(type default)
			)
			(layer "F.Fab")
		)
		(fp_circle
			(center -2.60604 -1.09982)
			(end -2.09804 -1.09982)
			(stroke
				(width 0.1)
				(type default)
			)
			(fill no)
			(layer "F.Fab")
		)
		(fp_text user "18"
			(at -2.413 -2.81305 0)
			(unlocked yes)
			(layer "F.SilkS")
			(effects
				(font
					(size 0.635 0.4064)
					(thickness 0.1524)
				)
			)
		)
		(fp_text user "5"
			(at -2.286 2.90195 0)
			(unlocked yes)
			(layer "F.SilkS")
			(effects
				(font
					(size 0.635 0.4064)
					(thickness 0.1524)
				)
			)
		)
		(fp_text user "6"
			(at -0.333502 3.002788 0)
			(unlocked yes)
			(layer "F.SilkS")
			(effects
				(font
					(size 0.635 0.4064)
					(thickness 0.1524)
				)
			)
		)
		(fp_text user "7"
			(at 0.484124 3.003296 0)
			(unlocked yes)
			(layer "F.SilkS")
			(effects
				(font
					(size 0.635 0.4064)
					(thickness 0.1524)
				)
			)
		)
		(fp_text user "8"
			(at 2.413 3.02895 0)
			(unlocked yes)
			(layer "F.SilkS")
			(effects
				(font
					(size 0.635 0.4064)
					(thickness 0.1524)
				)
			)
		)
		(fp_text user "13"
			(at 2.667 -2.50825 0)
			(unlocked yes)
			(layer "F.SilkS")
			(effects
				(font
					(size 0.635 0.4064)
					(thickness 0.1524)
				)
			)
		)
		(fp_text user "12"
			(at 3.175 -1.23825 0)
			(unlocked yes)
			(layer "F.SilkS")
			(effects
				(font
					(size 0.635 0.4064)
					(thickness 0.1524)
				)
			)
		)
		(fp_text user "5"
			(at -2.286 1.29667 0)
			(unlocked yes)
			(layer "F.Fab")
			(effects
				(font
					(size 0.7874 0.5842)
					(thickness 0.1524)
				)
			)
		)
		(fp_text user "18"
			(at -1.884934 -2.4638 0)
			(unlocked yes)
			(layer "F.Fab")
			(effects
				(font
					(size 0.7874 0.5842)
					(thickness 0.1524)
				)
			)
		)
		(fp_text user "6"
			(at -1.397 2.56667 0)
			(unlocked yes)
			(layer "F.Fab")
			(effects
				(font
					(size 0.7874 0.5842)
					(thickness 0.1524)
				)
			)
		)
		(fp_text user "13"
			(at 0.889 -2.25933 0)
			(unlocked yes)
			(layer "F.Fab")
			(effects
				(font
					(size 0.7874 0.5842)
					(thickness 0.1524)
				)
			)
		)
		(fp_text user "7"
			(at 1.524 2.43967 0)
			(unlocked yes)
			(layer "F.Fab")
			(effects
				(font
					(size 0.7874 0.5842)
					(thickness 0.1524)
				)
			)
		)
		(fp_text user "8"
			(at 2.286 1.29667 0)
			(unlocked yes)
			(layer "F.Fab")
			(effects
				(font
					(size 0.7874 0.5842)
					(thickness 0.1524)
				)
			)
		)
		(fp_text user "12"
			(at 2.54 -1.49733 0)
			(unlocked yes)
			(layer "F.Fab")
			(effects
				(font
					(size 0.7874 0.5842)
					(thickness 0.1524)
				)
			)
		)
		(pad "1" smd rect
			(at -1.649984 -0.94996)
			(size 0.6096 0.3048)
			(layers "F.Cu" "F.Mask" "F.Paste")
			(net "XP1R0V_BT")
		)
		(pad "2" smd rect
			(at -1.374902 -0.350012)
			(size 1.143 0.4064)
			(layers "F.Cu" "F.Mask" "F.Paste")
			(net "VIN_XP1R0V")
		)
		(pad "3" smd rect
			(at -1.374902 0.299974)
			(size 1.143 0.3048)
			(layers "F.Cu" "F.Mask" "F.Paste")
			(net "SG")
		)
		(pad "4" smd rect
			(at -1.374902 0.849884)
			(size 1.143 0.3048)
			(layers "F.Cu" "F.Mask" "F.Paste")
			(net "SG")
		)
		(pad "5" smd rect
			(at -1.374902 1.400048)
			(size 1.143 0.3048)
			(layers "F.Cu" "F.Mask" "F.Paste")
			(net "SG")
		)
		(pad "6" smd rect
			(at -0.32512 0.599948)
			(size 0.2032 2.6924)
			(layers "F.Cu" "F.Mask" "F.Paste")
			(net "XP1R0V_SW")
		)
		(pad "7" smd rect
			(at 0.32512 0.599948)
			(size 0.2032 2.6924)
			(layers "F.Cu" "F.Mask" "F.Paste")
			(net "XP1R0V_SW")
		)
		(pad "8" smd rect
			(at 1.374902 1.400048)
			(size 1.143 0.3048)
			(layers "F.Cu" "F.Mask" "F.Paste")
			(net "SG")
		)
		(pad "9" smd rect
			(at 1.374902 0.849884)
			(size 1.143 0.3048)
			(layers "F.Cu" "F.Mask" "F.Paste")
			(net "SG")
		)
		(pad "10" smd rect
			(at 1.374902 0.299974)
			(size 1.143 0.3048)
			(layers "F.Cu" "F.Mask" "F.Paste")
			(net "SG")
		)
		(pad "11" smd rect
			(at 1.374902 -0.350012)
			(size 1.143 0.4064)
			(layers "F.Cu" "F.Mask" "F.Paste")
			(net "VIN_XP1R0V")
		)
		(pad "12" smd rect
			(at 1.649984 -0.94996)
			(size 0.6096 0.3048)
			(layers "F.Cu" "F.Mask" "F.Paste")
			(net "XP1R0V_AGND")
		)
		(pad "13" smd rect
			(at 1.374902 -1.649984)
			(size 0.508 0.6096)
			(layers "F.Cu" "F.Mask" "F.Paste")
			(net "XP1R0V_RT")
		)
		(pad "14" smd rect
			(at 0.750062 -1.649984)
			(size 0.254 0.6096)
			(layers "F.Cu" "F.Mask" "F.Paste")
			(net "XP1R0V_FB_R_TO_AGND")
		)
		(pad "15" smd rect
			(at 0.249936 -1.649984)
			(size 0.254 0.6096)
			(layers "F.Cu" "F.Mask" "F.Paste")
			(net "XP1R0V_COMP")
		)
		(pad "16" smd rect
			(at -0.249936 -1.649984)
			(size 0.254 0.6096)
			(layers "F.Cu" "F.Mask" "F.Paste")
			(net "XP1R0V_SS")
		)
		(pad "17" smd rect
			(at -0.750062 -1.649984)
			(size 0.254 0.6096)
			(layers "F.Cu" "F.Mask" "F.Paste")
			(net "UNNAMED_523_CAPACITOR_I7_1")
		)
		(pad "18" smd rect
			(at -1.374902 -1.649984)
			(size 0.508 0.6096)
			(layers "F.Cu" "F.Mask" "F.Paste")
			(net "XP1R0V_PG")
		)
	)
	(footprint ""
		(layer "F.Cu")
		(at 101.092 -20.955 90)
		(property "Reference" "Y4"
			(at -3.83667 -0.762 0)
			(unlocked yes)
			(layer "F.SilkS")
			(effects
				(font
					(size 0.7874 0.5842)
					(thickness 0.1524)
				)
			)
		)
		(property "Value" ""
			(at 0 0 90)
			(layer "F.Fab")
			(effects
				(font
					(size 1.27 1.27)
				)
			)
		)
		(property "User Part Number" "PARTNUM*"
			(at 0 6.106668 90)
			(unlocked yes)
			(layer "Cmts.User")
			(hide yes)
			(effects
				(font
					(size 0.7874 0.5842)
					(thickness 0.1524)
				)
			)
		)
		(property "Device Type" "OSC6P_V2-A130-00004-AW"
			(at 0 4.912868 90)
			(unlocked yes)
			(layer "F.Fab")
			(hide yes)
			(effects
				(font
					(size 0.7874 0.5842)
					(thickness 0.1524)
				)
			)
		)
		(duplicate_pad_numbers_are_jumpers no)
		(fp_line
			(start 2.803906 -3.803904)
			(end 2.803906 3.803904)
			(stroke
				(width 0.1)
				(type default)
			)
			(layer "F.SilkS")
		)
		(fp_line
			(start -2.803906 -3.803904)
			(end 2.803906 -3.803904)
			(stroke
				(width 0.1)
				(type default)
			)
			(layer "F.SilkS")
		)
		(fp_line
			(start 2.803906 3.803904)
			(end -2.803906 3.803904)
			(stroke
				(width 0.1)
				(type default)
			)
			(layer "F.SilkS")
		)
		(fp_line
			(start -2.803906 3.803904)
			(end -2.803906 -3.803904)
			(stroke
				(width 0.1)
				(type default)
			)
			(layer "F.SilkS")
		)
		(fp_rect
			(start -3.057906 -4.057904)
			(end 3.057906 4.057904)
			(stroke
				(width 0)
				(type default)
			)
			(fill no)
			(layer "F.CrtYd")
		)
		(fp_line
			(start 2.549906 -3.549904)
			(end 2.549906 3.549904)
			(stroke
				(width 0.1)
				(type default)
			)
			(layer "F.Fab")
		)
		(fp_line
			(start -2.549906 -3.549904)
			(end 2.549906 -3.549904)
			(stroke
				(width 0.1)
				(type default)
			)
			(layer "F.Fab")
		)
		(fp_line
			(start 2.549906 3.549904)
			(end -2.549906 3.549904)
			(stroke
				(width 0.1)
				(type default)
			)
			(layer "F.Fab")
		)
		(fp_line
			(start -2.549906 3.549904)
			(end -2.549906 -3.549904)
			(stroke
				(width 0.1)
				(type default)
			)
			(layer "F.Fab")
		)
		(fp_text user "1"
			(at -3.480562 -2.712212 90)
			(unlocked yes)
			(layer "F.SilkS")
			(effects
				(font
					(size 0.7874 0.5842)
					(thickness 0.1524)
				)
			)
		)
		(fp_text user "3"
			(at -3.584194 2.45237 90)
			(unlocked yes)
			(layer "F.SilkS")
			(effects
				(font
					(size 0.7874 0.5842)
					(thickness 0.1524)
				)
			)
		)
		(fp_text user "6"
			(at 2.13233 -4.064 0)
			(unlocked yes)
			(layer "F.Fab")
			(effects
				(font
					(size 0.7874 0.5842)
					(thickness 0.1524)
				)
			)
		)
		(fp_text user "1"
			(at -3.253232 -2.611882 0)
			(unlocked yes)
			(layer "F.Fab")
			(effects
				(font
					(size 0.7874 0.5842)
					(thickness 0.1524)
				)
			)
		)
		(fp_text user "3"
			(at -3.356864 2.5527 0)
			(unlocked yes)
			(layer "F.Fab")
			(effects
				(font
					(size 0.7874 0.5842)
					(thickness 0.1524)
				)
			)
		)
		(fp_text user "4"
			(at 1.87833 3.937 0)
			(unlocked yes)
			(layer "F.Fab")
			(effects
				(font
					(size 0.7874 0.5842)
					(thickness 0.1524)
				)
			)
		)
		(pad "1" smd rect
			(at -1.849882 -2.54 90)
			(size 0.9906 1.397)
			(layers "F.Cu" "F.Mask" "F.Paste")
			(net "CLK_125M_OE")
		)
		(pad "2" smd rect
			(at -1.849882 0 90)
			(size 0.9906 1.397)
			(layers "F.Cu" "F.Mask" "F.Paste")
			(net "Net_762")
		)
		(pad "3" smd rect
			(at -1.849882 2.54 90)
			(size 0.9906 1.397)
			(layers "F.Cu" "F.Mask" "F.Paste")
			(net "SG")
		)
		(pad "4" smd rect
			(at 1.849882 2.54 90)
			(size 0.9906 1.397)
			(layers "F.Cu" "F.Mask" "F.Paste")
			(net "OSC_125M_CLKP")
		)
		(pad "5" smd rect
			(at 1.849882 0 90)
			(size 0.9906 1.397)
			(layers "F.Cu" "F.Mask" "F.Paste")
			(net "OSC_125M_CLKN")
		)
		(pad "6" smd rect
			(at 1.849882 -2.54 90)
			(size 0.9906 1.397)
			(layers "F.Cu" "F.Mask" "F.Paste")
			(net "VDD3V3_OSC_125M")
		)
		(zone
			(layer "F.Cu")
			(hatch none 0.5)
			(connect_pads
				(clearance 0)
			)
			(min_thickness 0.25)
			(keepout
				(tracks allowed)
				(vias not_allowed)
				(pads allowed)
				(copperpour not_allowed)
				(footprints allowed)
			)
			(placement
				(enabled no)
				(sheetname "")
			)
			(fill
				(thermal_gap 0.5)
				(thermal_bridge_width 0.5)
				(island_removal_mode 0)
			)
			(polygon
				(pts
					(xy 97.542096 -18.405094) (xy 104.641904 -18.405094) (xy 104.641904 -23.504906) (xy 97.542096 -23.504906)
				)
			)
			(polygon
				(pts
					(xy 99.2505 -19.600418) (xy 99.2505 -18.609818) (xy 97.8535 -18.609818) (xy 97.8535 -19.600418)
				)
			)
			(polygon
				(pts
					(xy 99.2505 -23.300182) (xy 99.2505 -22.309582) (xy 97.8535 -22.309582) (xy 97.8535 -23.300182)
				)
			)
			(polygon
				(pts
					(xy 101.7905 -19.600418) (xy 101.7905 -18.609818) (xy 100.3935 -18.609818) (xy 100.3935 -19.600418)
				)
			)
			(polygon
				(pts
					(xy 101.7905 -23.300182) (xy 101.7905 -22.309582) (xy 100.3935 -22.309582) (xy 100.3935 -23.300182)
				)
			)
			(polygon
				(pts
					(xy 104.3305 -19.600418) (xy 104.3305 -18.609818) (xy 102.9335 -18.609818) (xy 102.9335 -19.600418)
				)
			)
			(polygon
				(pts
					(xy 104.3305 -23.300182) (xy 104.3305 -22.309582) (xy 102.9335 -22.309582) (xy 102.9335 -23.300182)
				)
			)
		)
	)
)
